FILE_TYPE = CONNECTIVITY;
{Allegro Design Entry HDL 17.4-2019 S026 (4007227) 1/17/2022}
"PAGE_NUMBER" = 349;
0"NC";
1"GND\g";
2"P5V_AUX\g";
3"GND\g";
4"P3V3_AUX\g";
5"P3V_BAT_R\g";
6"SCM_VDD_RTC\g";
7"GND\g";
8"I3C_BMC_SWB_SDA"CDS_PHYS_NET_NAME"I3C_BMC_SWB_SDA";
9"I3C_BMC_SWB_SCL"CDS_PHYS_NET_NAME"I3C_BMC_SWB_SCL";
10"RST_MB_STBY_N";
11"SGPIO_SCM_DO_<0>";
12"P3V3_AUX\g";
13"PVDD18_S5_P0\g";
14"SMB_CPU_5_SDA";
15"SMB_CPU_5_SCL";
16"GND\g";
17"P3V3_AUX\g";
18"GND\g";
19"P3V3_AUX\g";
20"SMB_MUX_RT_ROM_R1_SDA";
21"SMB_HOST_CLK_3V3AUX_SDA_R1";
22"SMB_MUX_RT_ROM_R1_SCL";
23"SMB_HOST_CLK_GEN2_3V3AUX_SDA";
24"SMB_1_PLD_3V3AUX_SCL";
25"SMB_HOST_CLK_GEN2_3V3AUX_SCL";
26"SMB_HOST_CLK_3V3AUX_SCL_R1";
27"SMB_1_PLD_3V3AUX_SDA";
28"SMB_SCM_2_R6_SCL";
29"SMB_SCM_2_R6_SDA";
30"SMB_VR_3V3AUX_SCL";
31"SMB_VR_3V3STBY_SCL";
32"SMB_VR_3V3AUX_SDA";
33"JTAG_SCM_TDO_R";
34"SMB_SCM_2_R3_SCL";
35"SMB_HOST_CLK_3V3AUX_SDA";
36"SMB_2_PLD_3V3AUX_SDA_R1";
37"SMB_2_PLD_3V3AUX_SCL_R1";
38"SMB_HOST_CLK_3V3AUX_SCL";
39"SMB_9ZXL045_P0_SCL";
40"SMB_9ZXL045_P1_SDA";
41"SMB_9ZXL045_P1_SCL";
42"SMB_9ZXL045_P0_SDA";
43"SMB_HOST_CLK_3V3AUX_SCL"CDS_PHYS_NET_NAME"SMB_HOST_CLK_3V3AUX_SCL";
44"SMB_PMBUS_3V3AUX_SDA";
45"SMB_SML1_PMBUS_HSC_SDA";
46"SMB_SML1_PMBUS_HSC_SCL";
47"SMB_HOST_CLK_3V3AUX_SDA"CDS_PHYS_NET_NAME"SMB_HOST_CLK_3V3AUX_SDA";
48"JTAG_SCM_TDI_R";
49"SMB_CPU_5_SCL";
50"P0V9_RETIMER_CPU1_PMSDA";
51"JTAG_SCM_TDO";
52"SMB_CPU_5_SDA";
53"SMB_CPU0_CPU1_SEC_SCL";
54"SMB_CPU0_CPU1_APML_SDA";
55"SMB_FAN_3V3AUX_SDA"CDS_PHYS_NET_NAME"SMB_FAN_3V3AUX_SDA";
56"SMB_FAN_3V3AUX_SCL"CDS_PHYS_NET_NAME"SMB_FAN_3V3AUX_SCL";
57"SMB_PMBUS_3V3AUX_SDA";
58"SMB_CPU0_CPU1_APML_SCL";
59"SMB_CPU0_CPU1_SEC_SDA";
60"SMB_1_PLD_3V3AUX_SCL";
61"SMB_1_PLD_3V3AUX_SDA";
62"SMB_PMBUS_3V3AUX_SCL";
63"P0V9_RETIMER_CPU1_PMSCL";
64"SMB_PMBUS_3V3AUX_SCL";
65"UART_VCC_J8";
66"SCM_SPARE_1";
67"SCM_SPARE_0";
68"SGPIO_SCM_INTR_N";
69"SGPIO_SCM_RESET_N";
70"JTAG_SCM_DBREQ_N";
71"SGPIO_SCM_LD_<1>";
72"SGPIO_SCM_DI_<1>";
73"SGPIO_SCM_CLK_<1>";
74"UART_CPU0_SCM_LVC3_UART1_R_RX";
75"UART_CPU0_SCM_LVC3_UART1_TX";
76"SMB_OCP_SFF_3V3AUX_SCL";
77"SMB_OCP_SFF_3V3AUX_SDA";
78"SMB_2_BMC_GPU_SDA"CDS_PHYS_NET_NAME"SMB_2_BMC_GPU_SDA";
79"SMB_2_BMC_GPU_SCL"CDS_PHYS_NET_NAME"SMB_2_BMC_GPU_SCL";
80"SGPIO_SCM_CLK_<0>";
81"SGPIO_SCM_LD_<0>";
82"SMB_OCP_V3_2_3V3AUX_SCL";
83"SMB_OCP_V3_2_3V3AUX_SDA";
84"SGPIO_SCM_DO_<1>";
85"SGPIO_SCM_DI_<0>";
86"SMB_SCM_2_R3_SDA";
87"JTAG_SCM_TDI";
88"SMB_SCM_2_R4_SCL";
89"SMB_SCM_2_R4_SDA";
90"SMB_1_BMC_GPU_SCL"CDS_PHYS_NET_NAME"SMB_1_BMC_GPU_SCL";
91"SMB_1_BMC_GPU_SDA"CDS_PHYS_NET_NAME"SMB_1_BMC_GPU_SDA";
92"SMB_SML1_PMBUS_HSC_R1_SDA";
93"SMB_SML1_PMBUS_HSC_R1_SCL";
94"SMB_SCM_2_R5_SDA";
95"SMB_SCM_2_R5_SCL";
96"SMB_1_PLD_3V3AUX_SDA_R1";
97"SMB_1_PLD_3V3AUX_SCL_R1";
98"SMB_SCM_2_R1_SCL";
99"SMB_SCM_2_R2_SDA";
100"SMB_SCM_2_R2_SCL";
101"SMB_MUX_RT_R1_SDA";
102"SMB_VR_3V3STBY_SDA";
103"SMB_SCM_2_R1_SDA";
104"P0V9_RETIMER_CPU0_PMSCL";
105"P0V9_RETIMER_CPU0_PMSDA";
106"SMB_MUX_RT_R1_SCL";
107"SMB_CPU_5_R1_SDA";
108"SMB_CPU_5_R1_SCL";
%"Q_RES"
"1","(-525,2100)","0","pure_quanta","I10";
;
LOCATION"R1321"
$SEC"1"
CDS_SEC"1"
VALUE"33"
PACK_TYPE"0402LF"
TOLERANCE"5%"
MATERIAL"CHIP"
WATTAGE"1/16W"
CDS_LIB"pure_quanta"
PART_NUMBER"CS03302JB10";
"B"
$PN"2"98;
"A"
$PN"1"31;
%"UNIVERSAL_GND"
"1","(4250,1075)","2","pure_quanta_power","I111";
;
CDS_LIB"pure_quanta_power"
HDL_POWER"GND";
"A"1;
%"Q_CAP"
"1","(4250,1275)","0","pure_quanta","I112";
;
LOCATION"C63"
$SEC"1"
CDS_SEC"1"
TOLERANCE"5%"
PACK_TYPE"C0402"
VOLTAGE"50V"
VALUE"220PF"
CDS_LIB"pure_quanta"
MATERIAL"C0G"
PART_NUMBER"CH12206JB00";
"B"
$PN"2"1;
"A"
$PN"1"74;
%"Q_RES"
"1","(4450,1225)","1","pure_quanta","I113";
;
LOCATION"R130"
$SEC"1"
CDS_SEC"1"
MATERIAL"EMPTY"
PACK_TYPE"0402LF"
WATTAGE"1/16W"
VALUE"10K"
TOLERANCE"5%"
CDS_LIB"pure_quanta"
PART_NUMBER"CS31002JB08";
"B"
$PN"2"2;
"A"
$PN"1"65;
%"P1V0"
"1","(4450,1450)","0","pure_quanta_power","I114";
;
HDL_POWER"P5V_AUX"
CDS_LIB"pure_quanta_power";
"A"2;
%"Q_RES"
"1","(4275,2075)","0","pure_quanta","I115";
;
LOCATION"R3243"
$SEC"1"
CDS_SEC"1"
TOLERANCE"5%"
MATERIAL"EMPTY"
VALUE"2.2K"
CDS_LIB"pure_quanta"
PACK_TYPE"0402LF"
WATTAGE"1/16W"
PART_NUMBER"CS22202JB07";
"B"
$PN"2"19;
"A"
$PN"1"83;
%"Q_RES"
"2","(4675,1200)","0","pure_quanta","I116";
;
LOCATION"R131"
$SEC"1"
CDS_SEC"1"
PACK_TYPE"0402LF"
VALUE"10K"
TOLERANCE"5%"
MATERIAL"CHIP"
WATTAGE"1/16W"
CDS_LIB"pure_quanta"
PART_NUMBER"CS31002JB08";
"A"
$PN"1"4;
"B"
$PN"2"65;
%"UNIVERSAL_GND"
"1","(4850,1300)","2","pure_quanta_power","I117";
;
CDS_LIB"pure_quanta_power"
HDL_POWER"GND";
"A"3;
%"UNIVERSAL_POWER"
"1","(4675,1450)","0","pure_quanta_power","I118";
;
HDL_POWER"P3V3_AUX"
CDS_LIB"pure_quanta_power"
BOM_COST"VR_SYSTEM ";
"A"4;
%"Q_RES"
"1","(4275,2125)","0","pure_quanta","I119";
;
LOCATION"R3242"
$SEC"1"
CDS_SEC"1"
MATERIAL"EMPTY"
TOLERANCE"5%"
VALUE"2.2K"
WATTAGE"1/16W"
PACK_TYPE"0402LF"
CDS_LIB"pure_quanta"
PART_NUMBER"CS22202JB07";
"B"
$PN"2"19;
"A"
$PN"1"82;
%"Q_RES"
"1","(4275,2425)","0","pure_quanta","I120";
;
LOCATION"R3240"
$SEC"1"
CDS_SEC"1"
MATERIAL"EMPTY"
VALUE"2.2K"
TOLERANCE"5%"
WATTAGE"1/16W"
PACK_TYPE"0402LF"
CDS_LIB"pure_quanta"
PART_NUMBER"CS22202JB07";
"B"
$PN"2"19;
"A"
$PN"1"76;
%"Q_RES"
"1","(4275,2650)","0","pure_quanta","I121";
;
LOCATION"R3227"
$SEC"1"
CDS_SEC"1"
MATERIAL"EMPTY"
VALUE"2.2K"
TOLERANCE"5%"
CDS_LIB"pure_quanta"
WATTAGE"1/16W"
PACK_TYPE"0402LF"
PART_NUMBER"CS22202JB07";
"B"
$PN"2"19;
"A"
$PN"1"91;
%"Q_RES"
"1","(4275,2700)","0","pure_quanta","I122";
;
LOCATION"R3226"
$SEC"1"
CDS_SEC"1"
MATERIAL"EMPTY"
VALUE"2.2K"
TOLERANCE"5%"
WATTAGE"1/16W"
PACK_TYPE"0402LF"
CDS_LIB"pure_quanta"
PART_NUMBER"CS22202JB07";
"B"
$PN"2"19;
"A"
$PN"1"90;
%"Q_RES"
"1","(4275,3050)","0","pure_quanta","I123";
;
LOCATION"R3004"
$SEC"1"
CDS_SEC"1"
MATERIAL"EMPTY"
TOLERANCE"5%"
VALUE"2.2K"
PACK_TYPE"0402LF"
WATTAGE"1/16W"
CDS_LIB"pure_quanta"
PART_NUMBER"CS22202JB07";
"B"
$PN"2"19;
"A"
$PN"1"78;
%"Q_RES"
"1","(4275,3100)","0","pure_quanta","I124";
;
LOCATION"R2999"
$SEC"1"
CDS_SEC"1"
MATERIAL"EMPTY"
TOLERANCE"5%"
VALUE"2.2K"
WATTAGE"1/16W"
PACK_TYPE"0402LF"
CDS_LIB"pure_quanta"
PART_NUMBER"CS22202JB07";
"B"
$PN"2"19;
"A"
$PN"1"79;
%"Q_RES"
"1","(4275,3425)","0","pure_quanta","I125";
;
LOCATION"R2213"
$SEC"1"
CDS_SEC"1"
MATERIAL"EMPTY"
TOLERANCE"5%"
VALUE"2.2K"
PACK_TYPE"0402LF"
WATTAGE"1/16W"
CDS_LIB"pure_quanta"
PART_NUMBER"CS22202JB07";
"B"
$PN"2"19;
"A"
$PN"1"47;
%"Q_RES"
"1","(4275,3475)","0","pure_quanta","I126";
;
LOCATION"R2212"
$SEC"1"
CDS_SEC"1"
WATTAGE"1/16W"
PACK_TYPE"0402LF"
MATERIAL"EMPTY"
VALUE"2.2K"
TOLERANCE"5%"
CDS_LIB"pure_quanta"
PART_NUMBER"CS22202JB07";
"B"
$PN"2"19;
"A"
$PN"1"43;
%"Q_RES"
"1","(4275,3725)","0","pure_quanta","I127";
;
LOCATION"R1460"
$SEC"1"
CDS_SEC"1"
MATERIAL"EMPTY"
TOLERANCE"5%"
VALUE"2.2K"
PACK_TYPE"0402LF"
WATTAGE"1/16W"
CDS_LIB"pure_quanta"
PART_NUMBER"CS22202JB07";
"B"
$PN"2"19;
"A"
$PN"1"8;
%"Q_RES"
"1","(4275,3775)","0","pure_quanta","I128";
;
LOCATION"R332"
$SEC"1"
CDS_SEC"1"
WATTAGE"1/16W"
MATERIAL"EMPTY"
TOLERANCE"5%"
VALUE"2.2K"
PACK_TYPE"0402LF"
CDS_LIB"pure_quanta"
PART_NUMBER"CS22202JB07";
"B"
$PN"2"19;
"A"
$PN"1"9;
%"Q_RES"
"1","(4275,4125)","0","pure_quanta","I129";
;
LOCATION"R331"
$SEC"1"
CDS_SEC"1"
MATERIAL"EMPTY"
TOLERANCE"5%"
VALUE"2.2K"
WATTAGE"1/16W"
PACK_TYPE"0402LF"
CDS_LIB"pure_quanta"
PART_NUMBER"CS22202JB07";
"B"
$PN"2"19;
"A"
$PN"1"55;
%"Q_RES"
"1","(4275,4175)","0","pure_quanta","I130";
;
LOCATION"R330"
$SEC"1"
CDS_SEC"1"
PACK_TYPE"0402LF"
MATERIAL"EMPTY"
TOLERANCE"5%"
VALUE"2.2K"
WATTAGE"1/16W"
CDS_LIB"pure_quanta"
PART_NUMBER"CS22202JB07";
"B"
$PN"2"19;
"A"
$PN"1"56;
%"Q_RES"
"1","(4275,4525)","0","pure_quanta","I131";
;
LOCATION"R6036"
$SEC"1"
CDS_SEC"1"
WATTAGE"1/16W"
VALUE"2K"
TOLERANCE"1%"
MATERIAL"EMPTY"
PACK_TYPE"0402LF"
CDS_LIB"pure_quanta"
PART_NUMBER"CS22002FB07";
"B"
$PN"2"19;
"A"
$PN"1"60;
%"Q_RES"
"1","(4275,4475)","0","pure_quanta","I132";
;
LOCATION"R6037"
$SEC"1"
CDS_SEC"1"
PACK_TYPE"0402LF"
TOLERANCE"1%"
MATERIAL"EMPTY"
VALUE"2K"
WATTAGE"1/16W"
CDS_LIB"pure_quanta"
PART_NUMBER"CS22002FB07";
"B"
$PN"2"19;
"A"
$PN"1"61;
%"Q_RES"
"1","(4275,4725)","0","pure_quanta","I133";
;
LOCATION"R329"
$SEC"1"
CDS_SEC"1"
TOLERANCE"1%"
MATERIAL"EMPTY"
VALUE"2K"
PACK_TYPE"0402LF"
WATTAGE"1/16W"
CDS_LIB"pure_quanta"
PART_NUMBER"CS22002FB07";
"B"
$PN"2"19;
"A"
$PN"1"57;
%"Q_RES"
"1","(4275,4775)","0","pure_quanta","I134";
;
LOCATION"R1386"
$SEC"1"
CDS_SEC"1"
VALUE"2K"
PACK_TYPE"0402LF"
WATTAGE"1/16W"
TOLERANCE"1%"
MATERIAL"EMPTY"
CDS_LIB"pure_quanta"
PART_NUMBER"CS22002FB07";
"B"
$PN"2"19;
"A"
$PN"1"62;
%"Q_RES"
"1","(4275,4975)","0","pure_quanta","I135";
;
LOCATION"R1385"
$SEC"1"
CDS_SEC"1"
MATERIAL"EMPTY"
VALUE"2K"
TOLERANCE"1%"
CDS_LIB"pure_quanta"
WATTAGE"1/16W"
PACK_TYPE"0402LF"
PART_NUMBER"CS22002FB07";
"B"
$PN"2"19;
"A"
$PN"1"59;
%"Q_RES"
"1","(4275,5025)","0","pure_quanta","I136";
;
LOCATION"R1384"
$SEC"1"
CDS_SEC"1"
TOLERANCE"1%"
MATERIAL"EMPTY"
WATTAGE"1/16W"
VALUE"2K"
PACK_TYPE"0402LF"
CDS_LIB"pure_quanta"
PART_NUMBER"CS22002FB07";
"B"
$PN"2"19;
"A"
$PN"1"53;
%"Q_RES"
"1","(4275,5225)","0","pure_quanta","I137";
;
LOCATION"R3062"
$SEC"1"
CDS_SEC"1"
TOLERANCE"1%"
VALUE"2K"
MATERIAL"EMPTY"
PACK_TYPE"0402LF"
WATTAGE"1/16W"
CDS_LIB"pure_quanta"
PART_NUMBER"CS22002FB07";
"B"
$PN"2"19;
"A"
$PN"1"54;
%"Q_RES"
"1","(4275,5275)","0","pure_quanta","I138";
;
LOCATION"R1319"
$SEC"1"
CDS_SEC"1"
VALUE"2K"
PACK_TYPE"0402LF"
WATTAGE"1/16W"
TOLERANCE"1%"
MATERIAL"EMPTY"
CDS_LIB"pure_quanta"
PART_NUMBER"CS22002FB07";
"B"
$PN"2"19;
"A"
$PN"1"58;
%"UNIVERSAL_POWER"
"1","(4825,5800)","0","pure_quanta_power","I139";
;
HDL_POWER"P3V3_AUX"
CDS_LIB"pure_quanta_power";
"A"19;
%"Q_RES"
"2","(5500,5875)","0","pure_quanta","I142";
;
LOCATION"R889"
$SEC"1"
CDS_SEC"1"
VALUE"10K"
PACK_TYPE"0402LF"
WATTAGE"1/16W"
MATERIAL"EMPTY"
TOLERANCE"5%"
CDS_LIB"pure_quanta"
PART_NUMBER"CS31002JB08";
"A"
$PN"1"67;
"B"
$PN"2"18;
%"GND"
"1","(5700,5525)","0","pure_quanta_power","I143";
;
BOM_COST"MEM"
SIZE"1B"
CDS_LIB"pure_quanta_power"
HDL_POWER"GND";
"A<SIZE-1..0>\NAC"18;
%"Q_RES"
"2","(5700,5875)","0","pure_quanta","I144";
;
LOCATION"R891"
$SEC"1"
CDS_SEC"1"
PACK_TYPE"0402LF"
VALUE"10K"
TOLERANCE"5%"
MATERIAL"EMPTY"
WATTAGE"1/16W"
CDS_LIB"pure_quanta"
PART_NUMBER"CS31002JB08";
"A"
$PN"1"66;
"B"
$PN"2"18;
%"Q_RES"
"2","(5500,6350)","0","pure_quanta","I145";
;
LOCATION"R888"
$SEC"1"
CDS_SEC"1"
PACK_TYPE"0402LF"
MATERIAL"EMPTY"
WATTAGE"1/16W"
TOLERANCE"5%"
VALUE"10K"
CDS_LIB"pure_quanta"
PART_NUMBER"CS31002JB08";
"A"
$PN"1"17;
"B"
$PN"2"67;
%"VCC_CORE"
"1","(5500,6625)","0","pure_quanta_power","I146";
;
HDL_POWER"P3V3_AUX"
CDS_LIB"pure_quanta_power";
"A"17;
%"Q_RES"
"2","(5700,6350)","0","pure_quanta","I147";
;
LOCATION"R890"
$SEC"1"
CDS_SEC"1"
PACK_TYPE"0402LF"
MATERIAL"EMPTY"
WATTAGE"1/16W"
TOLERANCE"5%"
VALUE"10K"
CDS_LIB"pure_quanta"
PART_NUMBER"CS31002JB08";
"A"
$PN"1"17;
"B"
$PN"2"66;
%"CONN4_HFK1040L0P1L7H"
"1","(5350,1575)","0","pure_quanta","I148";
;
LOCATION"J8"
$SEC"1"
CDS_SEC"1"
PART_TYPE"THLF"
MATERIAL"IO"
VALUE"CONN4_HFK1040-L0P1L-7H"
CDS_LIB"pure_quanta"
NEEDS_NO_SIZE"TRUE"
CDS_LMAN_SYM_OUTLINE"-75,125,75,-125"
PART_NUMBER"DFHD04MS460";
"1"
$PN"1"65;
"2"
$PN"2"74;
"3"
$PN"3"75;
"4"
$PN"4"3;
%"Q_RES"
"1","(4275,2375)","0","pure_quanta","I149";
;
LOCATION"R3241"
$SEC"1"
CDS_SEC"1"
VALUE"2.2K"
TOLERANCE"5%"
MATERIAL"EMPTY"
PACK_TYPE"0402LF"
WATTAGE"1/16W"
CDS_LIB"pure_quanta"
PART_NUMBER"CS22202JB07";
"B"
$PN"2"19;
"A"
$PN"1"77;
%"Q_RES"
"1","(-1125,3475)","2","pure_quanta","I150";
;
LOCATION"R6066"
$SEC"1"
CDS_SEC"1"
MATERIAL"EMPTY"
VALUE"0"
PACK_TYPE"0402LF"
TOLERANCE"5%"
WATTAGE"1/16W"
CDS_LIB"pure_quanta"
PART_NUMBER"CS00002JB13";
"B"
$PN"2"87;
"A"
$PN"1"48;
%"Q_RES"
"1","(-1125,2925)","2","pure_quanta","I151";
;
LOCATION"R6068"
$SEC"1"
CDS_SEC"1"
VALUE"0"
MATERIAL"EMPTY"
CDS_LIB"pure_quanta"
WATTAGE"1/16W"
TOLERANCE"5%"
PACK_TYPE"0402LF"
PART_NUMBER"CS00002JB13";
"B"
$PN"2"51;
"A"
$PN"1"33;
%"Q_RES"
"1","(-1125,2750)","2","pure_quanta","I158";
;
LOCATION"R6069"
$SEC"1"
CDS_SEC"1"
VALUE"0"
MATERIAL"CHIP"
CDS_LIB"pure_quanta"
WATTAGE"1/16W"
TOLERANCE"5%"
PACK_TYPE"0402LF"
PART_NUMBER"CS00002JB13";
"B"
$PN"2"51;
"A"
$PN"1"48;
%"Q_RES"
"1","(-1125,3325)","2","pure_quanta","I159";
;
LOCATION"R6067"
$SEC"1"
CDS_SEC"1"
MATERIAL"CHIP"
VALUE"0"
CDS_LIB"pure_quanta"
WATTAGE"1/16W"
TOLERANCE"5%"
PACK_TYPE"0402LF"
PART_NUMBER"CS00002JB13";
"B"
$PN"2"87;
"A"
$PN"1"33;
%"Q_RES"
"1","(-2100,5350)","0","pure_quanta","I161";
;
LOCATION"R6070"
$SEC"1"
CDS_SEC"1"
MATERIAL"EMPTY"
VALUE"4.7K"
CDS_LIB"pure_quanta"
PACK_TYPE"0402LF"
TOLERANCE"5%"
WATTAGE"1/16W"
PART_NUMBER"CS24702JB10";
"B"
$PN"2"70;
"A"
$PN"1"12;
%"Q_RES"
"1","(-250,4550)","0","pure_quanta","I17";
;
LOCATION"R633"
$SEC"1"
CDS_SEC"1"
VALUE"2.2K"
MATERIAL"CHIP"
PACK_TYPE"0402LF"
TOLERANCE"5%"
WATTAGE"1/16W"
CDS_LIB"pure_quanta"
PART_NUMBER"CS22202JB07";
"B"
$PN"2"14;
"A"
$PN"1"13;
%"Q_RES"
"1","(2700,6550)","0","pure_quanta","I172";
;
LOCATION"R348"
$SEC"1"
CDS_SEC"1"
TOLERANCE"1%"
VALUE"33.2"
MATERIAL"CHIP"
CDS_LIB"pure_quanta"
PACK_TYPE"0402LF"
WATTAGE"1/16W"
PART_NUMBER"CS03322FB03";
"B"
$PN"2"92;
"A"
$PN"1"45;
%"Q_RES"
"1","(2700,6600)","0","pure_quanta","I173";
;
LOCATION"R347"
$SEC"1"
CDS_SEC"1"
VALUE"33.2"
MATERIAL"CHIP"
TOLERANCE"1%"
PACK_TYPE"0402LF"
WATTAGE"1/16W"
CDS_LIB"pure_quanta"
PART_NUMBER"CS03322FB03";
"B"
$PN"2"93;
"A"
$PN"1"46;
%"Q_RES"
"1","(-1650,1700)","0","pure_quanta","I176";
;
LOCATION"R1497"
$SEC"1"
CDS_SEC"1"
VALUE"33"
CDS_LIB"pure_quanta"
WATTAGE"1/16W"
MATERIAL"CHIP"
TOLERANCE"5%"
PACK_TYPE"0402LF"
PART_NUMBER"CS03302JB10";
"B"
$PN"2"34;
"A"
$PN"1"30;
%"Q_RES"
"1","(-250,4600)","0","pure_quanta","I18";
;
LOCATION"R632"
$SEC"1"
CDS_SEC"1"
VALUE"2.2K"
MATERIAL"CHIP"
PACK_TYPE"0402LF"
TOLERANCE"5%"
WATTAGE"1/16W"
CDS_LIB"pure_quanta"
PART_NUMBER"CS22202JB07";
"B"
$PN"2"15;
"A"
$PN"1"13;
%"Q_RES"
"1","(-1125,1450)","0","pure_quanta","I181";
;
LOCATION"R6076"
$SEC"1"
CDS_SEC"1"
VALUE"33"
PACK_TYPE"0402LF"
TOLERANCE"5%"
MATERIAL"CHIP"
WATTAGE"1/16W"
CDS_LIB"pure_quanta"
PART_NUMBER"CS03302JB10";
"B"
$PN"2"88;
"A"
$PN"1"34;
%"Q_RES"
"1","(-1125,1350)","0","pure_quanta","I182";
;
LOCATION"R6077"
$SEC"1"
CDS_SEC"1"
VALUE"33"
PACK_TYPE"0402LF"
TOLERANCE"5%"
MATERIAL"CHIP"
WATTAGE"1/16W"
CDS_LIB"pure_quanta"
PART_NUMBER"CS03302JB10";
"B"
$PN"2"89;
"A"
$PN"1"86;
%"Q_RES"
"1","(-1650,1600)","0","pure_quanta","I183";
;
LOCATION"R1498"
$SEC"1"
CDS_SEC"1"
VALUE"33"
PACK_TYPE"0402LF"
TOLERANCE"5%"
MATERIAL"CHIP"
WATTAGE"1/16W"
CDS_LIB"pure_quanta"
PART_NUMBER"CS03302JB10";
"B"
$PN"2"86;
"A"
$PN"1"32;
%"Q_RES"
"1","(1500,1425)","0","pure_quanta","I184";
;
LOCATION"R350"
$SEC"1"
CDS_SEC"1"
VALUE"33"
PACK_TYPE"0402LF"
TOLERANCE"5%"
MATERIAL"CHIP"
WATTAGE"1/16W"
CDS_LIB"pure_quanta"
PART_NUMBER"CS03302JB10";
"B"
$PN"2"94;
"A"
$PN"1"99;
%"Q_RES"
"1","(1500,1525)","0","pure_quanta","I185";
;
LOCATION"R349"
$SEC"1"
CDS_SEC"1"
VALUE"33"
PACK_TYPE"0402LF"
TOLERANCE"5%"
MATERIAL"CHIP"
WATTAGE"1/16W"
CDS_LIB"pure_quanta"
PART_NUMBER"CS03302JB10";
"B"
$PN"2"95;
"A"
$PN"1"100;
%"Q_RES"
"1","(2075,1025)","0","pure_quanta","I186";
;
LOCATION"R352"
$SEC"1"
CDS_SEC"1"
VALUE"33"
CDS_LIB"pure_quanta"
WATTAGE"1/16W"
MATERIAL"CHIP"
TOLERANCE"5%"
PACK_TYPE"0402LF"
PART_NUMBER"CS03302JB10";
"B"
$PN"2"29;
"A"
$PN"1"94;
%"Q_RES"
"1","(2075,1125)","0","pure_quanta","I187";
;
LOCATION"R351"
$SEC"1"
CDS_SEC"1"
VALUE"33"
CDS_LIB"pure_quanta"
PACK_TYPE"0402LF"
TOLERANCE"5%"
MATERIAL"CHIP"
WATTAGE"1/16W"
PART_NUMBER"CS03302JB10";
"B"
$PN"2"28;
"A"
$PN"1"95;
%"Q_RES"
"1","(3375,6500)","2","pure_quanta","I198";
;
LOCATION"R6784"
$SEC"1"
CDS_SEC"1"
VALUE"0"
MATERIAL"CHIP"
WATTAGE"1/16W"
TOLERANCE"5%"
PACK_TYPE"0402LF"
CDS_LIB"pure_quanta"
PART_NUMBER"CS00002JB13";
"B"
$PN"2"46;
"A"
$PN"1"106;
%"Q_RES"
"1","(3375,6450)","2","pure_quanta","I199";
;
LOCATION"R6785"
$SEC"1"
CDS_SEC"1"
MATERIAL"CHIP"
VALUE"0"
WATTAGE"1/16W"
TOLERANCE"5%"
PACK_TYPE"0402LF"
CDS_LIB"pure_quanta"
PART_NUMBER"CS00002JB13";
"B"
$PN"2"45;
"A"
$PN"1"101;
%"Q_RES"
"1","(-2100,5400)","0","pure_quanta","I20";
;
LOCATION"R6024"
$SEC"1"
CDS_SEC"1"
VALUE"4.7K"
MATERIAL"EMPTY"
PACK_TYPE"0402LF"
TOLERANCE"5%"
WATTAGE"1/16W"
CDS_LIB"pure_quanta"
PART_NUMBER"CS24702JB10";
"B"
$PN"2"68;
"A"
$PN"1"12;
%"Q_RES"
"1","(-125,2625)","0","pure_quanta","I206";
;
LOCATION"R6859"
$SEC"1"
CDS_SEC"1"
VALUE"0"
WATTAGE"1/16W"
MATERIAL"CHIP"
TOLERANCE"5%"
PACK_TYPE"0402LF"
CDS_LIB"pure_quanta"
PART_NUMBER"CS00002JB13";
"B"
$PN"2"50;
"A"
$PN"1"102;
%"Q_RES"
"1","(-125,2525)","0","pure_quanta","I207";
;
LOCATION"R6858"
$SEC"1"
CDS_SEC"1"
VALUE"0"
CDS_LIB"pure_quanta"
PACK_TYPE"0402LF"
TOLERANCE"5%"
MATERIAL"CHIP"
WATTAGE"1/16W"
PART_NUMBER"CS00002JB13";
"B"
$PN"2"63;
"A"
$PN"1"31;
%"Q_RES"
"1","(-2100,5450)","0","pure_quanta","I21";
;
LOCATION"R6023"
$SEC"1"
CDS_SEC"1"
MATERIAL"EMPTY"
VALUE"2K"
CDS_LIB"pure_quanta"
WATTAGE"1/16W"
TOLERANCE"5%"
PACK_TYPE"0402LF"
PART_NUMBER"TMP_QCS22002JB29";
"B"
$PN"2"71;
"A"
$PN"1"12;
%"Q_RES"
"1","(1425,5175)","0","pure_quanta","I218";
;
LOCATION"R6862"
$SEC"1"
CDS_SEC"1"
MATERIAL"CHIP"
VALUE"33"
CDS_LIB"pure_quanta"
WATTAGE"1/16W"
TOLERANCE"5%"
PACK_TYPE"0402LF"
PART_NUMBER"CS03302JB10";
"B"
$PN"2"41;
"A"
$PN"1"26;
%"Q_RES"
"1","(1425,5100)","0","pure_quanta","I219";
;
LOCATION"R6863"
$SEC"1"
CDS_SEC"1"
MATERIAL"CHIP"
VALUE"33"
CDS_LIB"pure_quanta"
PACK_TYPE"0402LF"
TOLERANCE"5%"
WATTAGE"1/16W"
PART_NUMBER"CS03302JB10";
"B"
$PN"2"40;
"A"
$PN"1"21;
%"Q_RES"
"1","(-2100,5550)","0","pure_quanta","I22";
;
LOCATION"R6021"
$SEC"1"
CDS_SEC"1"
VALUE"2K"
MATERIAL"EMPTY"
PACK_TYPE"0402LF"
TOLERANCE"5%"
WATTAGE"1/16W"
CDS_LIB"pure_quanta"
PART_NUMBER"TMP_QCS22002JB29";
"B"
$PN"2"73;
"A"
$PN"1"12;
%"Q_RES"
"1","(1425,4975)","0","pure_quanta","I220";
;
LOCATION"R6864"
$SEC"1"
CDS_SEC"1"
MATERIAL"CHIP"
VALUE"33"
CDS_LIB"pure_quanta"
PACK_TYPE"0402LF"
TOLERANCE"5%"
WATTAGE"1/16W"
PART_NUMBER"CS03302JB10";
"B"
$PN"2"39;
"A"
$PN"1"26;
%"Q_RES"
"1","(1425,4900)","0","pure_quanta","I221";
;
LOCATION"R6865"
$SEC"1"
CDS_SEC"1"
MATERIAL"CHIP"
VALUE"33"
CDS_LIB"pure_quanta"
PACK_TYPE"0402LF"
TOLERANCE"5%"
WATTAGE"1/16W"
PART_NUMBER"CS03302JB10";
"B"
$PN"2"42;
"A"
$PN"1"21;
%"Q_RES"
"1","(600,5525)","0","pure_quanta","I222";
;
LOCATION"R1516"
$SEC"1"
CDS_SEC"1"
WATTAGE"1/16W"
PACK_TYPE"0402LF"
MATERIAL"CHIP"
TOLERANCE"1%"
VALUE"33.2"
CDS_LIB"pure_quanta"
PART_NUMBER"CS03322FB03";
"B"
$PN"2"26;
"A"
$PN"1"38;
%"Q_RES"
"1","(600,5475)","0","pure_quanta","I223";
;
LOCATION"R1517"
$SEC"1"
CDS_SEC"1"
TOLERANCE"1%"
MATERIAL"CHIP"
VALUE"33.2"
WATTAGE"1/16W"
PACK_TYPE"0402LF"
CDS_LIB"pure_quanta"
PART_NUMBER"CS03322FB03";
"B"
$PN"2"21;
"A"
$PN"1"35;
%"Q_RES"
"1","(-1625,2375)","0","pure_quanta","I224";
;
LOCATION"R308"
$SEC"1"
CDS_SEC"1"
VALUE"33"
PACK_TYPE"0402LF"
TOLERANCE"5%"
MATERIAL"CHIP"
WATTAGE"1/16W"
CDS_LIB"pure_quanta"
PART_NUMBER"CS03302JB10";
"B"
$PN"2"31;
"A"
$PN"1"30;
%"Q_RES"
"1","(-1625,2275)","0","pure_quanta","I225";
;
LOCATION"R309"
SEC"1"
VALUE"33"
PACK_TYPE"0402LF"
SEC_TYPE"0402LF"
TOLERANCE"5%"
MATERIAL"CHIP"
WATTAGE"1/16W"
CDS_LIB"pure_quanta"
PART_NUMBER"CS03302JB10";
"B"
$PN"2"102;
"A"
$PN"1"32;
%"Q_RES"
"1","(2875,850)","0","pure_quanta","I226";
;
LOCATION"R6856"
$SEC"1"
CDS_SEC"1"
VALUE"33"
CDS_LIB"pure_quanta"
WATTAGE"1/16W"
MATERIAL"CHIP"
TOLERANCE"5%"
PACK_TYPE"0402LF"
PART_NUMBER"CS03302JB10";
"B"
$PN"2"104;
"A"
$PN"1"28;
%"Q_RES"
"1","(2875,750)","0","pure_quanta","I227";
;
LOCATION"R6857"
$SEC"1"
CDS_SEC"1"
VALUE"33"
CDS_LIB"pure_quanta"
WATTAGE"1/16W"
MATERIAL"CHIP"
TOLERANCE"5%"
PACK_TYPE"0402LF"
PART_NUMBER"CS03302JB10";
"B"
$PN"2"105;
"A"
$PN"1"29;
%"Q_RES"
"1","(2550,5525)","2","pure_quanta","I228";
;
LOCATION"R6782"
SEC"1"
VALUE"33"
MATERIAL"CHIP"
WATTAGE"1/16W"
TOLERANCE"5%"
CDS_LIB"pure_quanta"
SEC_TYPE"0402LF"
PACK_TYPE"0402LF"
PART_NUMBER"CS03302JB10";
"B"
$PN"2"26;
"A"
$PN"1"22;
%"Q_RES"
"1","(2550,5475)","2","pure_quanta","I229";
;
LOCATION"R6783"
$SEC"1"
CDS_SEC"1"
VALUE"33"
MATERIAL"CHIP"
CDS_LIB"pure_quanta"
WATTAGE"1/16W"
TOLERANCE"5%"
PACK_TYPE"0402LF"
PART_NUMBER"CS03302JB10";
"B"
$PN"2"21;
"A"
$PN"1"20;
%"Q_RES"
"1","(-2100,5500)","0","pure_quanta","I23";
;
LOCATION"R6022"
$SEC"1"
CDS_SEC"1"
VALUE"2K"
MATERIAL"EMPTY"
PACK_TYPE"0402LF"
TOLERANCE"5%"
WATTAGE"1/16W"
CDS_LIB"pure_quanta"
PART_NUMBER"TMP_QCS22002JB29";
"B"
$PN"2"72;
"A"
$PN"1"12;
%"Q_RES"
"1","(-1475,6375)","0","pure_quanta","I231";
;
LOCATION"R364"
SEC"1"
WATTAGE"1/16W"
MATERIAL"CHIP"
PACK_TYPE"0402LF"
VALUE"0"
TOLERANCE"5%"
SEC_TYPE"0402LF"
CDS_LIB"pure_quanta"
PART_NUMBER"CS00002JB13";
"B"
$PN"2"6;
"A"
$PN"1"5;
%"Q_RES"
"1","(-2100,5600)","0","pure_quanta","I24";
;
LOCATION"R6020"
$SEC"1"
CDS_SEC"1"
MATERIAL"EMPTY"
VALUE"2K"
PACK_TYPE"0402LF"
TOLERANCE"5%"
WATTAGE"1/16W"
CDS_LIB"pure_quanta"
PART_NUMBER"TMP_QCS22002JB29";
"B"
$PN"2"84;
"A"
$PN"1"12;
%"Q_RES"
"1","(-2100,5650)","0","pure_quanta","I25";
;
LOCATION"R6019"
$SEC"1"
CDS_SEC"1"
VALUE"2K"
MATERIAL"EMPTY"
PACK_TYPE"0402LF"
TOLERANCE"5%"
WATTAGE"1/16W"
CDS_LIB"pure_quanta"
PART_NUMBER"TMP_QCS22002JB29";
"B"
$PN"2"81;
"A"
$PN"1"12;
%"UNIVERSAL_POWER"
"1","(-2525,6075)","0","pure_quanta_power","I26";
;
HDL_POWER"P3V3_AUX"
CDS_LIB"pure_quanta_power";
"A"12;
%"Q_RES"
"1","(-2100,5700)","0","pure_quanta","I27";
;
LOCATION"R6018"
$SEC"1"
CDS_SEC"1"
VALUE"2K"
MATERIAL"EMPTY"
PACK_TYPE"0402LF"
TOLERANCE"5%"
WATTAGE"1/16W"
CDS_LIB"pure_quanta"
PART_NUMBER"TMP_QCS22002JB29";
"B"
$PN"2"85;
"A"
$PN"1"12;
%"Q_RES"
"1","(-2100,5750)","0","pure_quanta","I28";
;
LOCATION"R6017"
$SEC"1"
CDS_SEC"1"
MATERIAL"EMPTY"
VALUE"2K"
CDS_LIB"pure_quanta"
WATTAGE"1/16W"
TOLERANCE"5%"
PACK_TYPE"0402LF"
PART_NUMBER"TMP_QCS22002JB29";
"B"
$PN"2"80;
"A"
$PN"1"12;
%"Q_RES"
"1","(-2100,5800)","0","pure_quanta","I29";
;
LOCATION"R6016"
$SEC"1"
CDS_SEC"1"
VALUE"2K"
MATERIAL"EMPTY"
PACK_TYPE"0402LF"
TOLERANCE"5%"
WATTAGE"1/16W"
CDS_LIB"pure_quanta"
PART_NUMBER"TMP_QCS22002JB29";
"B"
$PN"2"11;
"A"
$PN"1"12;
%"Q_RES"
"1","(-2100,6000)","0","pure_quanta","I30";
;
LOCATION"R1546"
$SEC"1"
CDS_SEC"1"
VALUE"1K"
WATTAGE"1/16W"
MATERIAL"CHIP"
PACK_TYPE"0402LF"
CDS_LIB"pure_quanta"
TOLERANCE"1%"
PART_NUMBER"CS21002FB06";
"B"
$PN"2"10;
"A"
$PN"1"12;
%"UNIVERSAL_POWER"
"1","(-2050,6650)","0","pure_quanta_power","I31";
;
HDL_POWER"P3V_BAT_R"
CDS_LIB"pure_quanta_power";
"A"5;
%"Q_RES"
"1","(-1600,4850)","0","pure_quanta","I32";
;
LOCATION"R6027"
$SEC"1"
CDS_SEC"1"
VALUE"4.7K"
MATERIAL"EMPTY"
WATTAGE"1/16W"
TOLERANCE"5%"
PACK_TYPE"0402LF"
CDS_LIB"pure_quanta"
PART_NUMBER"CS24702JB10";
"B"
$PN"2"16;
"A"
$PN"1"69;
%"UNIVERSAL_POWER"
"1","(-675,4850)","0","pure_quanta_power","I43";
;
HDL_POWER"PVDD18_S5_P0"
CDS_LIB"pure_quanta_power";
"A"13;
%"UNIVERSAL_GND"
"1","(-1225,4675)","0","pure_quanta_power","I44";
;
CDS_LIB"pure_quanta_power"
HDL_POWER"GND";
"A"16;
%"VCC_CORE"
"1","(-975,6675)","0","pure_quanta_power","I46";
;
HDL_POWER"SCM_VDD_RTC"
CDS_LIB"pure_quanta_power";
"A"6;
%"Q_RES"
"1","(500,1750)","0","pure_quanta","I48";
;
LOCATION"R1496"
$SEC"1"
CDS_SEC"1"
VALUE"33"
WATTAGE"1/16W"
MATERIAL"CHIP"
TOLERANCE"5%"
PACK_TYPE"0402LF"
CDS_LIB"pure_quanta"
PART_NUMBER"CS03302JB10";
"B"
$PN"2"99;
"A"
$PN"1"103;
%"Q_RES"
"1","(500,1850)","0","pure_quanta","I49";
;
LOCATION"R1495"
$SEC"1"
CDS_SEC"1"
VALUE"33"
WATTAGE"1/16W"
MATERIAL"CHIP"
TOLERANCE"5%"
PACK_TYPE"0402LF"
CDS_LIB"pure_quanta"
PART_NUMBER"CS03302JB10";
"B"
$PN"2"100;
"A"
$PN"1"98;
%"Q_RES"
"1","(500,4200)","2","pure_quanta","I56";
;
LOCATION"R1453"
$SEC"1"
CDS_SEC"1"
VALUE"0"
CDS_LIB"pure_quanta"
PACK_TYPE"0402LF"
TOLERANCE"5%"
MATERIAL"CHIP"
WATTAGE"1/16W"
PART_NUMBER"CS00002JB13";
"B"
$PN"2"107;
"A"
$PN"1"52;
%"Q_RES"
"1","(500,4300)","2","pure_quanta","I57";
;
LOCATION"R1447"
$SEC"1"
CDS_SEC"1"
VALUE"0"
CDS_LIB"pure_quanta"
PACK_TYPE"0402LF"
TOLERANCE"5%"
MATERIAL"CHIP"
WATTAGE"1/16W"
PART_NUMBER"CS00002JB13";
"B"
$PN"2"108;
"A"
$PN"1"49;
%"UNIVERSAL_GND"
"1","(4050,1075)","2","pure_quanta_power","I66";
;
CDS_LIB"pure_quanta_power"
HDL_POWER"GND";
"A"7;
%"Q_CAP"
"1","(4050,1275)","0","pure_quanta","I69";
;
LOCATION"C62"
$SEC"1"
CDS_SEC"1"
PACK_TYPE"C0402"
TOLERANCE"5%"
VALUE"220PF"
VOLTAGE"50V"
CDS_LIB"pure_quanta"
MATERIAL"C0G"
PART_NUMBER"CH12206JB00";
"B"
$PN"2"7;
"A"
$PN"1"75;
%"Q_RES"
"1","(1750,5775)","0","pure_quanta","I81";
;
LOCATION"R3340"
$SEC"1"
CDS_SEC"1"
PACK_TYPE"0402LF"
VALUE"33.2"
MATERIAL"CHIP"
TOLERANCE"1%"
WATTAGE"1/16W"
CDS_LIB"pure_quanta"
PART_NUMBER"CS03322FB03";
"B"
$PN"2"25;
"A"
$PN"1"38;
%"Q_RES"
"1","(1750,5725)","0","pure_quanta","I82";
;
LOCATION"R3341"
$SEC"1"
CDS_SEC"1"
VALUE"33.2"
TOLERANCE"1%"
MATERIAL"CHIP"
CDS_LIB"pure_quanta"
WATTAGE"1/16W"
PACK_TYPE"0402LF"
PART_NUMBER"CS03322FB03";
"B"
$PN"2"23;
"A"
$PN"1"35;
%"Q_RES"
"1","(1950,6075)","0","pure_quanta","I83";
;
LOCATION"R4151"
$SEC"1"
CDS_SEC"1"
TOLERANCE"1%"
VALUE"33.2"
WATTAGE"1/16W"
MATERIAL"CHIP"
PACK_TYPE"0402LF"
CDS_LIB"pure_quanta"
PART_NUMBER"CS03322FB03";
"B"
$PN"2"37;
"A"
$PN"1"24;
%"Q_RES"
"1","(1950,6025)","0","pure_quanta","I84";
;
LOCATION"R4152"
$SEC"1"
CDS_SEC"1"
TOLERANCE"1%"
VALUE"33.2"
MATERIAL"CHIP"
CDS_LIB"pure_quanta"
PACK_TYPE"0402LF"
WATTAGE"1/16W"
PART_NUMBER"CS03322FB03";
"B"
$PN"2"36;
"A"
$PN"1"27;
%"Q_RES"
"1","(1950,6350)","0","pure_quanta","I89";
;
LOCATION"R4149"
$SEC"1"
CDS_SEC"1"
TOLERANCE"1%"
VALUE"33.2"
WATTAGE"1/16W"
PACK_TYPE"0402LF"
MATERIAL"CHIP"
CDS_LIB"pure_quanta"
PART_NUMBER"CS03322FB03";
"B"
$PN"2"97;
"A"
$PN"1"24;
%"Q_RES"
"1","(-525,2000)","0","pure_quanta","I9";
;
LOCATION"R1494"
$SEC"1"
CDS_SEC"1"
VALUE"33"
PACK_TYPE"0402LF"
TOLERANCE"5%"
MATERIAL"CHIP"
WATTAGE"1/16W"
CDS_LIB"pure_quanta"
PART_NUMBER"CS03302JB10";
"B"
$PN"2"103;
"A"
$PN"1"102;
%"Q_RES"
"1","(1950,6300)","0","pure_quanta","I90";
;
LOCATION"R4150"
$SEC"1"
CDS_SEC"1"
VALUE"33.2"
TOLERANCE"1%"
MATERIAL"CHIP"
PACK_TYPE"0402LF"
WATTAGE"1/16W"
CDS_LIB"pure_quanta"
PART_NUMBER"CS03322FB03";
"B"
$PN"2"96;
"A"
$PN"1"27;
%"Q_RES"
"1","(1925,6775)","0","pure_quanta","I91";
;
LOCATION"R2995"
$SEC"1"
CDS_SEC"1"
WATTAGE"1/16W"
TOLERANCE"1%"
VALUE"33.2"
PACK_TYPE"0402LF"
MATERIAL"CHIP"
CDS_LIB"pure_quanta"
PART_NUMBER"CS03322FB03";
"B"
$PN"2"46;
"A"
$PN"1"64;
%"Q_RES"
"1","(1925,6725)","0","pure_quanta","I92";
;
LOCATION"R2996"
$SEC"1"
CDS_SEC"1"
MATERIAL"CHIP"
VALUE"33.2"
TOLERANCE"1%"
CDS_LIB"pure_quanta"
WATTAGE"1/16W"
PACK_TYPE"0402LF"
PART_NUMBER"CS03322FB03";
"B"
$PN"2"45;
"A"
$PN"1"44;
END.
